# T6G (Grand Teton) — schematic netlist excerpt (pin names and nets, part order shuffled) for the footprints in the layout excerpt that follows; sources: Cadence DE-HDL packaged netlist, KiCad conversion of 04192023_DAF0TMB3IC0_F0TG_MB_C_brd_V02_OCP.brd

R3206  Q_RES  0 5% EMPTY  pkg 0402LF  page 138 : A = FM_NCSI_OCP_V3_2_R_OE ; B = FB_BMC_ISOLATE1
R3591  Q_RES  33.2 1% CHIP  pkg 0402LF  page 251 : A = SMB_INA230_3V3AUX_SDA ; B = SMB_INA230_3_3V3AUX_SDA_R

(kicad_pcb
	(version 20260206)
	(generator "pcbnew")
	(generator_version "10.0")
	(general
		(thickness 1.6)
		(legacy_teardrops no)
	)
	(paper "A4")
	(title_block
		(title "04192023_DAF0TMB3IC0_F0TG_MB_C_brd_V02_OCP.brd")
		(comment 1 "Grand Teton / footprints 898-899 of 8354")
	)
	(layers
		(0 "F.Cu" signal "TOP")
		(4 "In1.Cu" signal "GND")
		(6 "In2.Cu" signal "IN1")
		(8 "In3.Cu" signal "GND1")
		(10 "In4.Cu" signal "IN2")
		(12 "In5.Cu" signal "GND2")
		(14 "In6.Cu" signal "IN3")
		(16 "In7.Cu" signal "GND3")
		(18 "In8.Cu" signal "VCC")
		(20 "In9.Cu" signal "VCC1")
		(22 "In10.Cu" signal "GND4")
		(24 "In11.Cu" signal "IN4")
		(26 "In12.Cu" signal "GND5")
		(28 "In13.Cu" signal "IN5")
		(30 "In14.Cu" signal "GND6")
		(32 "In15.Cu" signal "IN6")
		(34 "In16.Cu" signal "GND7")
		(2 "B.Cu" signal "BOTTOM")
		(9 "F.Adhes" user "F.Adhesive")
		(11 "B.Adhes" user "B.Adhesive")
		(13 "F.Paste" user "Package Geometry/Pastemask Top")
		(15 "B.Paste" user "Package Geometry/Pastemask Bottom")
		(5 "F.SilkS" user "Ref Des/Silkscreen Top")
		(7 "B.SilkS" user "Ref Des/Silkscreen Bottom")
		(1 "F.Mask" user "Board Geometry/Soldermask Top")
		(3 "B.Mask" user "Board Geometry/Soldermask Bottom")
		(17 "Dwgs.User" user "User.Drawings")
		(19 "Cmts.User" user "User.Comments")
		(21 "Eco1.User" user "User.Eco1")
		(23 "Eco2.User" user "User.Eco2")
		(25 "Edge.Cuts" user "Board Geometry/Outline")
		(27 "Margin" user)
		(31 "F.CrtYd" user "Package Geometry/Place Bound Top")
		(29 "B.CrtYd" user "Package Geometry/Place Bound Bottom")
		(35 "F.Fab" user "Ref Des/Assembly Top")
		(33 "B.Fab" user "Ref Des/Assembly Bottom")
	)
	(footprint ""
		(layer "F.Cu")
		(at 49.38268 -35.804348 180)
		(property "Reference" "R3206"
			(at 0 0 180)
			(layer "F.SilkS")
			(hide yes)
			(effects
				(font
					(size 1.27 1.27)
				)
			)
		)
		(property "Value" ""
			(at 0 0 180)
			(layer "F.Fab")
			(effects
				(font
					(size 1.27 1.27)
				)
			)
		)
		(duplicate_pad_numbers_are_jumpers no)
		(fp_line
			(start 0.7874 0.4064)
			(end -0.7874 0.4064)
			(stroke
				(width 0.1524)
				(type default)
			)
			(layer "F.SilkS")
		)
		(fp_line
			(start 0.7874 -0.4064)
			(end 0.7874 0.4064)
			(stroke
				(width 0.1524)
				(type default)
			)
			(layer "F.SilkS")
		)
		(fp_line
			(start -0.7874 0.4064)
			(end -0.7874 -0.4064)
			(stroke
				(width 0.1524)
				(type default)
			)
			(layer "F.SilkS")
		)
		(fp_line
			(start -0.7874 -0.4064)
			(end 0.7874 -0.4064)
			(stroke
				(width 0.1524)
				(type default)
			)
			(layer "F.SilkS")
		)
		(fp_line
			(start 0.67945 0.3048)
			(end 0.120396 0.3048)
			(stroke
				(width 0.1)
				(type default)
			)
			(layer "F.Fab")
		)
		(fp_line
			(start 0.67945 -0.3048)
			(end 0.67945 0.3048)
			(stroke
				(width 0.1)
				(type default)
			)
			(layer "F.Fab")
		)
		(fp_line
			(start 0.12065 -0.2794)
			(end 0.12065 -0.3048)
			(stroke
				(width 0.1)
				(type default)
			)
			(layer "F.Fab")
		)
		(fp_line
			(start 0.12065 -0.3048)
			(end 0.67945 -0.3048)
			(stroke
				(width 0.1)
				(type default)
			)
			(layer "F.Fab")
		)
		(fp_line
			(start 0.120396 0.3048)
			(end 0.120396 0.2794)
			(stroke
				(width 0.1)
				(type default)
			)
			(layer "F.Fab")
		)
		(fp_line
			(start 0.120396 0.2794)
			(end -0.12065 0.2794)
			(stroke
				(width 0.1)
				(type default)
			)
			(layer "F.Fab")
		)
		(fp_line
			(start -0.12065 0.3048)
			(end -0.67945 0.3048)
			(stroke
				(width 0.1)
				(type default)
			)
			(layer "F.Fab")
		)
		(fp_line
			(start -0.12065 0.2794)
			(end -0.12065 0.3048)
			(stroke
				(width 0.1)
				(type default)
			)
			(layer "F.Fab")
		)
		(fp_line
			(start -0.12065 -0.2794)
			(end 0.12065 -0.2794)
			(stroke
				(width 0.1)
				(type default)
			)
			(layer "F.Fab")
		)
		(fp_line
			(start -0.12065 -0.305054)
			(end -0.12065 -0.2794)
			(stroke
				(width 0.1)
				(type default)
			)
			(layer "F.Fab")
		)
		(fp_line
			(start -0.67945 0.3048)
			(end -0.67945 -0.305054)
			(stroke
				(width 0.1)
				(type default)
			)
			(layer "F.Fab")
		)
		(fp_line
			(start -0.67945 -0.305054)
			(end -0.12065 -0.305054)
			(stroke
				(width 0.1)
				(type default)
			)
			(layer "F.Fab")
		)
		(pad "1" smd circle
			(at -0.40005 0 180)
			(size 0 0)
			(layers "F.Cu" "F.Mask" "F.Paste")
			(net "FM_NCSI_OCP_V3_2_R_OE")
		)
		(pad "2" smd circle
			(at 0.40005 0 180)
			(size 0 0)
			(layers "F.Cu" "F.Mask" "F.Paste")
			(net "FB_BMC_ISOLATE1")
		)
	)
	(footprint ""
		(layer "F.Cu")
		(at 151.966676 -50.739294 90)
		(property "Reference" "R3591"
			(at 0 0 90)
			(layer "F.SilkS")
			(hide yes)
			(effects
				(font
					(size 1.27 1.27)
				)
			)
		)
		(property "Value" ""
			(at 0 0 90)
			(layer "F.Fab")
			(effects
				(font
					(size 1.27 1.27)
				)
			)
		)
		(duplicate_pad_numbers_are_jumpers no)
		(fp_line
			(start 0.7874 -0.4064)
			(end 0.7874 0.4064)
			(stroke
				(width 0.1524)
				(type default)
			)
			(layer "F.SilkS")
		)
		(fp_line
			(start -0.7874 -0.4064)
			(end 0.7874 -0.4064)
			(stroke
				(width 0.1524)
				(type default)
			)
			(layer "F.SilkS")
		)
		(fp_line
			(start 0.7874 0.4064)
			(end -0.7874 0.4064)
			(stroke
				(width 0.1524)
				(type default)
			)
			(layer "F.SilkS")
		)
		(fp_line
			(start -0.7874 0.4064)
			(end -0.7874 -0.4064)
			(stroke
				(width 0.1524)
				(type default)
			)
			(layer "F.SilkS")
		)
		(fp_line
			(start -0.12065 -0.305054)
			(end -0.12065 -0.2794)
			(stroke
				(width 0.1)
				(type default)
			)
			(layer "F.Fab")
		)
		(fp_line
			(start -0.67945 -0.305054)
			(end -0.12065 -0.305054)
			(stroke
				(width 0.1)
				(type default)
			)
			(layer "F.Fab")
		)
		(fp_line
			(start 0.67945 -0.3048)
			(end 0.67945 0.3048)
			(stroke
				(width 0.1)
				(type default)
			)
			(layer "F.Fab")
		)
		(fp_line
			(start 0.12065 -0.3048)
			(end 0.67945 -0.3048)
			(stroke
				(width 0.1)
				(type default)
			)
			(layer "F.Fab")
		)
		(fp_line
			(start 0.12065 -0.2794)
			(end 0.12065 -0.3048)
			(stroke
				(width 0.1)
				(type default)
			)
			(layer "F.Fab")
		)
		(fp_line
			(start -0.12065 -0.2794)
			(end 0.12065 -0.2794)
			(stroke
				(width 0.1)
				(type default)
			)
			(layer "F.Fab")
		)
		(fp_line
			(start 0.120396 0.2794)
			(end -0.12065 0.2794)
			(stroke
				(width 0.1)
				(type default)
			)
			(layer "F.Fab")
		)
		(fp_line
			(start -0.12065 0.2794)
			(end -0.12065 0.3048)
			(stroke
				(width 0.1)
				(type default)
			)
			(layer "F.Fab")
		)
		(fp_line
			(start 0.67945 0.3048)
			(end 0.120396 0.3048)
			(stroke
				(width 0.1)
				(type default)
			)
			(layer "F.Fab")
		)
		(fp_line
			(start 0.120396 0.3048)
			(end 0.120396 0.2794)
			(stroke
				(width 0.1)
				(type default)
			)
			(layer "F.Fab")
		)
		(fp_line
			(start -0.12065 0.3048)
			(end -0.67945 0.3048)
			(stroke
				(width 0.1)
				(type default)
			)
			(layer "F.Fab")
		)
		(fp_line
			(start -0.67945 0.3048)
			(end -0.67945 -0.305054)
			(stroke
				(width 0.1)
				(type default)
			)
			(layer "F.Fab")
		)
		(pad "1" smd circle
			(at -0.40005 0 90)
			(size 0 0)
			(layers "F.Cu" "F.Mask" "F.Paste")
			(net "SMB_INA230_3V3AUX_SDA")
		)
		(pad "2" smd circle
			(at 0.40005 0 90)
			(size 0 0)
			(layers "F.Cu" "F.Mask" "F.Paste")
			(net "SMB_INA230_3_3V3AUX_SDA_R")
		)
	)
)
